(kicad_pcb
	(version 20241229)
	(generator "pcbnew")
	(generator_version "9.0")
	(general
		(thickness 1.294)
		(legacy_teardrops no)
	)
	(paper "A3")
	(title_block
		(title "Kintex 410T devboard")
		(date "2024-04-03")
		(rev "1.1.2")
		(comment 9 "footprints 90-95 of 975")
	)
	(layers
		(0 "F.Cu" mixed)
		(4 "In1.Cu" power)
		(6 "In2.Cu" power)
		(8 "In3.Cu" mixed)
		(10 "In4.Cu" power)
		(12 "In5.Cu" mixed)
		(14 "In6.Cu" power)
		(16 "In7.Cu" mixed)
		(18 "In8.Cu" power)
		(2 "B.Cu" mixed)
		(9 "F.Adhes" user "F.Adhesive")
		(11 "B.Adhes" user "B.Adhesive")
		(13 "F.Paste" user)
		(15 "B.Paste" user)
		(5 "F.SilkS" user "F.Silkscreen")
		(7 "B.SilkS" user "B.Silkscreen")
		(1 "F.Mask" user)
		(3 "B.Mask" user)
		(17 "Dwgs.User" user "User.Drawings")
		(19 "Cmts.User" user "User.Comments")
		(21 "Eco1.User" user "User.Eco1")
		(23 "Eco2.User" user "User.Eco2")
		(25 "Edge.Cuts" user)
		(27 "Margin" user)
		(31 "F.CrtYd" user "F.Courtyard")
		(29 "B.CrtYd" user "B.Courtyard")
		(35 "F.Fab" user)
		(33 "B.Fab" user)
	)
	(footprint "antmicro-footprints:C_0402_1005Metric"
		(layer "F.Cu")
		(at 250.145 130.735)
		(descr "Capacitor SMD 0402")
		(tags "capacitor SMD 0402")
		(property "Reference" "C240"
			(at -1.395 -0.435 0)
			(layer "F.SilkS")
			(effects
				(font
					(size 0.7 0.7)
					(thickness 0.15)
				)
				(justify left bottom)
			)
		)
		(property "Value" "C_100n_0402"
			(at 0 1.169 0)
			(layer "F.Fab")
			(effects
				(font
					(size 0.7 0.7)
					(thickness 0.15)
				)
				(justify left bottom)
			)
		)
		(property "Description" "SMD Multilayer Ceramic Capacitor, 0.1 µF, 50 V, 0402 [1005 Metric], ± 10%, X5R, GRM Series"
			(at 0 0 0)
			(layer "F.Fab")
			(hide yes)
			(effects
				(font
					(size 1.27 1.27)
					(thickness 0.15)
				)
			)
		)
		(property "Author" "Antmicro"
			(at 0 0 0)
			(layer "F.Fab")
			(hide yes)
			(effects
				(font
					(size 1 1)
					(thickness 0.15)
				)
			)
		)
		(property "Dielectric" "X5R"
			(at 0 0 0)
			(layer "F.Fab")
			(hide yes)
			(effects
				(font
					(size 1 1)
					(thickness 0.15)
				)
			)
		)
		(property "License" "Apache-2.0"
			(at 0 0 0)
			(layer "F.Fab")
			(hide yes)
			(effects
				(font
					(size 1 1)
					(thickness 0.15)
				)
			)
		)
		(property "MPN" "GRM155R61H104KE14D"
			(at 0 0 0)
			(layer "F.Fab")
			(hide yes)
			(effects
				(font
					(size 1 1)
					(thickness 0.15)
				)
			)
		)
		(property "Manufacturer" "Murata"
			(at 0 0 0)
			(layer "F.Fab")
			(hide yes)
			(effects
				(font
					(size 1 1)
					(thickness 0.15)
				)
			)
		)
		(property "Val" "100n"
			(at 0 0 0)
			(layer "F.Fab")
			(hide yes)
			(effects
				(font
					(size 1 1)
					(thickness 0.15)
				)
			)
		)
		(property "Voltage" "50V"
			(at 0 0 0)
			(layer "F.Fab")
			(hide yes)
			(effects
				(font
					(size 1 1)
					(thickness 0.15)
				)
			)
		)
		(sheetname "USB PHY")
		(sheetfile "usb-phy.kicad_sch")
		(attr smd)
		(fp_rect
			(start -0.925 -0.47)
			(end 0.925 0.47)
			(stroke
				(width 0.05)
				(type default)
			)
			(fill no)
			(layer "F.CrtYd")
		)
		(fp_line
			(start -0.494 -0.25)
			(end 0.504 -0.25)
			(stroke
				(width 0.15)
				(type solid)
			)
			(layer "F.Fab")
		)
		(fp_line
			(start -0.494 0.248)
			(end -0.494 -0.25)
			(stroke
				(width 0.15)
				(type solid)
			)
			(layer "F.Fab")
		)
		(fp_line
			(start 0.504 -0.25)
			(end 0.504 0.248)
			(stroke
				(width 0.15)
				(type solid)
			)
			(layer "F.Fab")
		)
		(fp_line
			(start 0.504 0.248)
			(end -0.494 0.248)
			(stroke
				(width 0.15)
				(type solid)
			)
			(layer "F.Fab")
		)
		(pad "1" smd roundrect
			(at -0.48 0)
			(size 0.59 0.64)
			(layers "F.Cu" "F.Mask" "F.Paste")
			(roundrect_rratio 0.25)
			(net 1 "GND")
			(pintype "passive")
		)
		(pad "2" smd roundrect
			(at 0.48 0)
			(size 0.59 0.64)
			(layers "F.Cu" "F.Mask" "F.Paste")
			(roundrect_rratio 0.25)
			(net 707 "/USB PHY/FTDI_3V3")
			(pintype "passive")
		)
	)
	(footprint "antmicro-footprints:NetTie-2_SMD_Pad0.127mm"
		(layer "F.Cu")
		(at 239.4 124.073 -90)
		(descr "Net tie, 2 pin, 0.127mm  SMD pads")
		(tags "net tie")
		(property "Reference" "NT15"
			(at -0.128 -1.345 270)
			(layer "F.SilkS")
			(hide yes)
			(effects
				(font
					(size 0.7 0.7)
					(thickness 0.15)
				)
				(justify left bottom)
			)
		)
		(property "Value" "Net-Tie_2"
			(at 0 1.199 270)
			(layer "F.Fab")
			(effects
				(font
					(size 0.7 0.7)
					(thickness 0.15)
				)
				(justify left bottom)
			)
		)
		(property "Description" "Net tie, 2 pins"
			(at 0 0 270)
			(layer "F.Fab")
			(hide yes)
			(effects
				(font
					(size 1.27 1.27)
					(thickness 0.15)
				)
			)
		)
		(property "Author" "Antmicro"
			(at 115.327 363.473 0)
			(layer "F.Fab")
			(hide yes)
			(effects
				(font
					(size 1 1)
					(thickness 0.15)
				)
			)
		)
		(property "License" "Apache-2.0"
			(at 115.327 363.473 0)
			(layer "F.Fab")
			(hide yes)
			(effects
				(font
					(size 1 1)
					(thickness 0.15)
				)
			)
		)
		(property "MPN" ""
			(at 115.327 363.473 0)
			(layer "F.Fab")
			(hide yes)
			(effects
				(font
					(size 1 1)
					(thickness 0.15)
				)
			)
		)
		(property "Manufacturer" ""
			(at 115.327 363.473 0)
			(layer "F.Fab")
			(hide yes)
			(effects
				(font
					(size 1 1)
					(thickness 0.15)
				)
			)
		)
		(sheetname "FPGA Bank 12 & 13")
		(sheetfile "fpga-bank-12-13.kicad_sch")
		(attr exclude_from_pos_files)
		(net_tie_pad_groups "1, 2")
		(fp_poly
			(pts
				(xy -0.0635 -0.0635) (xy 0.0625 -0.0635) (xy 0.0625 0.0635) (xy -0.0635 0.0635)
			)
			(stroke
				(width 0)
				(type solid)
			)
			(fill yes)
			(layer "F.Cu")
		)
		(pad "1" smd roundrect
			(at -0.127 0 90)
			(size 0.127 0.127)
			(layers "F.Cu")
			(roundrect_rratio 0.5)
			(chamfer_ratio 0)
			(chamfer top_left bottom_left)
			(net 1328 "/SUP_MCU.TX1")
			(pinfunction "1")
			(pintype "passive")
		)
		(pad "2" smd roundrect
			(at 0.126 0 270)
			(size 0.127 0.127)
			(layers "F.Cu")
			(roundrect_rratio 0.5)
			(chamfer_ratio 0)
			(chamfer top_left bottom_left)
			(net 45 "/FPGA Bank 12 & 13/UART1.RX")
			(pinfunction "2")
			(pintype "passive")
		)
	)
	(footprint "antmicro-footprints:TP_SMD_0.75mm"
		(layer "F.Cu")
		(at 180.9 170.8)
		(property "Reference" "TP5"
			(at 0.5 0.7 0)
			(layer "F.SilkS")
			(effects
				(font
					(size 0.7 0.7)
					(thickness 0.15)
				)
				(justify left bottom)
			)
		)
		(property "Value" "TP_0.75mm_SMD"
			(at 0 1.2 0)
			(layer "F.Fab")
			(effects
				(font
					(size 0.7 0.7)
					(thickness 0.15)
				)
				(justify left bottom)
			)
		)
		(property "Description" "SMT test point"
			(at 0 0 0)
			(layer "F.Fab")
			(hide yes)
			(effects
				(font
					(size 1.27 1.27)
					(thickness 0.15)
				)
			)
		)
		(property "Author" "Antmicro"
			(at 0 0 0)
			(layer "F.Fab")
			(hide yes)
			(effects
				(font
					(size 1 1)
					(thickness 0.15)
				)
			)
		)
		(property "License" "Apache-2.0"
			(at 0 0 0)
			(layer "F.Fab")
			(hide yes)
			(effects
				(font
					(size 1 1)
					(thickness 0.15)
				)
			)
		)
		(property "MPN" ""
			(at 0 0 0)
			(layer "F.Fab")
			(hide yes)
			(effects
				(font
					(size 1 1)
					(thickness 0.15)
				)
			)
		)
		(property "Manufacturer" ""
			(at 0 0 0)
			(layer "F.Fab")
			(hide yes)
			(effects
				(font
					(size 1 1)
					(thickness 0.15)
				)
			)
		)
		(sheetname "DC-DC Converters")
		(sheetfile "dc-dc.kicad_sch")
		(attr exclude_from_pos_files)
		(pad "1" smd circle
			(at 0 0)
			(size 0.75 0.75)
			(layers "F.Cu" "F.Mask")
			(net 1336 "/I2C.SDA")
			(pinfunction "1")
			(pintype "passive")
		)
	)
	(footprint "antmicro-footprints:R_0402_1005Metric"
		(layer "F.Cu")
		(at 218.4 152.8)
		(descr "Resistor SMD 0402")
		(tags "resistor SMD 0402")
		(property "Reference" "R233"
			(at -3.6 0.35 0)
			(layer "F.SilkS")
			(effects
				(font
					(size 0.7 0.7)
					(thickness 0.15)
				)
				(justify left bottom)
			)
		)
		(property "Value" "R_10R_0402"
			(at 0 1.4 0)
			(layer "F.Fab")
			(effects
				(font
					(size 0.7 0.7)
					(thickness 0.15)
				)
				(justify left bottom)
			)
		)
		(property "Description" "SMD Chip Resistor, 10 ohm, ± 1%, 62.5 mW, 0402 [1005 Metric], Thick Film, General Purpose"
			(at 0 0 0)
			(layer "F.Fab")
			(hide yes)
			(effects
				(font
					(size 1.27 1.27)
					(thickness 0.15)
				)
			)
		)
		(property "Author" "Antmicro"
			(at 0 0 0)
			(layer "F.Fab")
			(hide yes)
			(effects
				(font
					(size 1 1)
					(thickness 0.15)
				)
			)
		)
		(property "License" "Apache-2.0"
			(at 0 0 0)
			(layer "F.Fab")
			(hide yes)
			(effects
				(font
					(size 1 1)
					(thickness 0.15)
				)
			)
		)
		(property "MPN" "CR0402-FX-10R0GLF"
			(at 0 0 0)
			(layer "F.Fab")
			(hide yes)
			(effects
				(font
					(size 1 1)
					(thickness 0.15)
				)
			)
		)
		(property "Manufacturer" "Bourns"
			(at 0 0 0)
			(layer "F.Fab")
			(hide yes)
			(effects
				(font
					(size 1 1)
					(thickness 0.15)
				)
			)
		)
		(property "Tolerance" "1%"
			(at 0 0 0)
			(layer "F.Fab")
			(hide yes)
			(effects
				(font
					(size 1 1)
					(thickness 0.15)
				)
			)
		)
		(property "Val" "10R"
			(at 0 0 0)
			(layer "F.Fab")
			(hide yes)
			(effects
				(font
					(size 1 1)
					(thickness 0.15)
				)
			)
		)
		(sheetname "HDMI + Ethernet")
		(sheetfile "hdmi-ethernet.kicad_sch")
		(attr smd)
		(fp_rect
			(start -0.925 -0.47)
			(end 0.925 0.47)
			(stroke
				(width 0.05)
				(type default)
			)
			(fill no)
			(layer "F.CrtYd")
		)
		(fp_rect
			(start -0.5 -0.25)
			(end 0.5 0.25)
			(stroke
				(width 0.15)
				(type solid)
			)
			(fill no)
			(layer "F.Fab")
		)
		(pad "1" smd roundrect
			(at -0.48 0)
			(size 0.59 0.64)
			(layers "F.Cu" "F.Mask" "F.Paste")
			(roundrect_rratio 0.25)
			(net 515 "/FPGA Bank 18 & 32/ETH_RMII.TXD1")
			(pintype "passive")
		)
		(pad "2" smd roundrect
			(at 0.48 0)
			(size 0.59 0.64)
			(layers "F.Cu" "F.Mask" "F.Paste")
			(roundrect_rratio 0.25)
			(net 950 "/HDMI + Ethernet/ETH_PHY_TXD1")
			(pintype "passive")
		)
	)
	(footprint "antmicro-footprints:PinSocket_2x6_P2.54mm_Drill1.04mm_Horizontal"
		(layer "F.Cu")
		(at 236.1875 80.1495)
		(property "Reference" "J6"
			(at 14.3125 -1.7495 0)
			(layer "F.SilkS")
			(effects
				(font
					(size 0.7 0.7)
					(thickness 0.15)
				)
				(justify left bottom)
			)
		)
		(property "Value" "PinSocket_2x6_P2.54mm_Drill1.04mm_Horizontal"
			(at 0 4.75 0)
			(layer "F.Fab")
			(effects
				(font
					(size 0.7 0.7)
					(thickness 0.15)
				)
				(justify left bottom)
			)
		)
		(property "Description" "PCB Receptacle, Board-to-Board, 2.54 mm, 2 Rows, 12 Contacts, Through Hole Mount Right Angle, SSW"
			(at 0 0 0)
			(layer "F.Fab")
			(hide yes)
			(effects
				(font
					(size 1.27 1.27)
					(thickness 0.15)
				)
			)
		)
		(property "Author" "Antmicro"
			(at 0 0 0)
			(layer "F.Fab")
			(hide yes)
			(effects
				(font
					(size 1 1)
					(thickness 0.15)
				)
			)
		)
		(property "License" "Apache-2.0"
			(at 0 0 0)
			(layer "F.Fab")
			(hide yes)
			(effects
				(font
					(size 1 1)
					(thickness 0.15)
				)
			)
		)
		(property "MPN" "SSW-106-02-G-D-RA"
			(at 0 0 0)
			(layer "F.Fab")
			(hide yes)
			(effects
				(font
					(size 1 1)
					(thickness 0.15)
				)
			)
		)
		(property "Manufacturer" "Samtec"
			(at 0 0 0)
			(layer "F.Fab")
			(hide yes)
			(effects
				(font
					(size 1 1)
					(thickness 0.15)
				)
			)
		)
		(sheetname "User GPIO + LED + button + DIP switch")
		(sheetfile "user-gpio.kicad_sch")
		(attr through_hole)
		(fp_line
			(start -1.526 -1.524)
			(end -1.526 -10.035)
			(stroke
				(width 0.15)
				(type solid)
			)
			(layer "F.SilkS")
		)
		(fp_line
			(start 14.223 -10.035)
			(end -1.526 -10.035)
			(stroke
				(width 0.15)
				(type solid)
			)
			(layer "F.SilkS")
		)
		(fp_line
			(start 14.223 -10.035)
			(end 14.223 -1.524)
			(stroke
				(width 0.15)
				(type solid)
			)
			(layer "F.SilkS")
		)
		(fp_line
			(start 14.223 -1.524)
			(end -1.526 -1.524)
			(stroke
				(width 0.15)
				(type solid)
			)
			(layer "F.SilkS")
		)
		(fp_circle
			(center -1.2 0)
			(end -1.15 0)
			(stroke
				(width 0.15)
				(type solid)
			)
			(fill yes)
			(layer "F.SilkS")
		)
		(fp_rect
			(start -1.9 -10.4)
			(end 14.6 3.6)
			(stroke
				(width 0.05)
				(type solid)
			)
			(fill no)
			(layer "F.CrtYd")
		)
		(fp_line
			(start -1.526 -10.035)
			(end 14.223 -10.035)
			(stroke
				(width 0.15)
				(type solid)
			)
			(layer "F.Fab")
		)
		(fp_line
			(start -1.526 -10.035)
			(end 14.223 -10.035)
			(stroke
				(width 0.15)
				(type solid)
			)
			(layer "F.Fab")
		)
		(fp_line
			(start -1.526 -1.524)
			(end -1.526 -10.035)
			(stroke
				(width 0.15)
				(type solid)
			)
			(layer "F.Fab")
		)
		(fp_line
			(start -1.526 -1.524)
			(end -1.526 -10.035)
			(stroke
				(width 0.15)
				(type solid)
			)
			(layer "F.Fab")
		)
		(fp_line
			(start 14.223 -10.035)
			(end 14.223 -1.524)
			(stroke
				(width 0.15)
				(type solid)
			)
			(layer "F.Fab")
		)
		(fp_line
			(start 14.223 -10.035)
			(end 14.223 -1.524)
			(stroke
				(width 0.15)
				(type solid)
			)
			(layer "F.Fab")
		)
		(fp_line
			(start 14.223 -1.524)
			(end -1.526 -1.524)
			(stroke
				(width 0.15)
				(type solid)
			)
			(layer "F.Fab")
		)
		(pad "1" thru_hole rect
			(at 0 0)
			(size 1.84 1.84)
			(drill 1.04)
			(layers "*.Cu" "*.Mask")
			(remove_unused_layers no)
			(net 816 "/User GPIO + LED + button + DIP switch/PMOD_B_7")
			(pintype "passive")
		)
		(pad "2" thru_hole circle
			(at 0 2.539)
			(size 1.84 1.84)
			(drill 1.04)
			(layers "*.Cu" "*.Mask")
			(remove_unused_layers no)
			(net 817 "/User GPIO + LED + button + DIP switch/PMOD_B_1")
			(pintype "passive")
		)
		(pad "3" thru_hole circle
			(at 2.539 0)
			(size 1.84 1.84)
			(drill 1.04)
			(layers "*.Cu" "*.Mask")
			(remove_unused_layers no)
			(net 814 "/User GPIO + LED + button + DIP switch/PMOD_B_8")
			(pintype "passive")
		)
		(pad "4" thru_hole circle
			(at 2.539 2.539)
			(size 1.8 1.8)
			(drill 1.04)
			(layers "*.Cu" "*.Mask")
			(remove_unused_layers no)
			(net 815 "/User GPIO + LED + button + DIP switch/PMOD_B_2")
			(pintype "passive")
		)
		(pad "5" thru_hole circle
			(at 5.078 0)
			(size 1.84 1.84)
			(drill 1.04)
			(layers "*.Cu" "*.Mask")
			(remove_unused_layers no)
			(net 812 "/User GPIO + LED + button + DIP switch/PMOD_B_9")
			(pintype "passive")
		)
		(pad "6" thru_hole circle
			(at 5.078 2.539)
			(size 1.84 1.84)
			(drill 1.04)
			(layers "*.Cu" "*.Mask")
			(remove_unused_layers no)
			(net 813 "/User GPIO + LED + button + DIP switch/PMOD_B_3")
			(pintype "passive")
		)
		(pad "7" thru_hole circle
			(at 7.618 0)
			(size 1.84 1.84)
			(drill 1.04)
			(layers "*.Cu" "*.Mask")
			(remove_unused_layers no)
			(net 810 "/User GPIO + LED + button + DIP switch/PMOD_B_10")
			(pintype "passive")
		)
		(pad "8" thru_hole circle
			(at 7.618 2.539)
			(size 1.84 1.84)
			(drill 1.04)
			(layers "*.Cu" "*.Mask")
			(remove_unused_layers no)
			(net 811 "/User GPIO + LED + button + DIP switch/PMOD_B_4")
			(pintype "passive")
		)
		(pad "9" thru_hole circle
			(at 10.159 0)
			(size 1.84 1.84)
			(drill 1.04)
			(layers "*.Cu" "*.Mask")
			(remove_unused_layers no)
			(net 1 "GND")
			(pintype "passive")
		)
		(pad "10" thru_hole circle
			(at 10.159 2.539)
			(size 1.84 1.84)
			(drill 1.04)
			(layers "*.Cu" "*.Mask")
			(remove_unused_layers no)
			(net 1 "GND")
			(pintype "passive")
		)
		(pad "11" thru_hole circle
			(at 12.698 0)
			(size 1.84 1.84)
			(drill 1.04)
			(layers "*.Cu" "*.Mask")
			(remove_unused_layers no)
			(net 24 "+3V3")
			(pintype "passive")
		)
		(pad "12" thru_hole circle
			(at 12.698 2.539)
			(size 1.84 1.84)
			(drill 1.04)
			(layers "*.Cu" "*.Mask")
			(remove_unused_layers no)
			(net 24 "+3V3")
			(pintype "passive")
		)
	)
	(footprint "antmicro-footprints:C_0603_1608Metric"
		(layer "F.Cu")
		(at 174.9 165.5 180)
		(descr "Capacitor SMD 0603")
		(tags "capacitor 0603")
		(property "Reference" "C330"
			(at 1 -0.4 0)
			(layer "F.SilkS")
			(effects
				(font
					(size 0.7 0.7)
					(thickness 0.15)
				)
				(justify right bottom)
			)
		)
		(property "Value" "C_22u_0603"
			(at 0 1.6 0)
			(layer "F.Fab")
			(effects
				(font
					(size 0.7 0.7)
					(thickness 0.15)
				)
				(justify right bottom)
			)
		)
		(property "Description" "SMD Multilayer Ceramic Capacitor, 22 µF, 6.3 V, 0603 [1608 Metric], ± 20%, X5R, GRM Series"
			(at 0 0 180)
			(layer "F.Fab")
			(hide yes)
			(effects
				(font
					(size 1.27 1.27)
					(thickness 0.15)
				)
			)
		)
		(property "Author" "Antmicro"
			(at 349.8 331 0)
			(layer "F.Fab")
			(hide yes)
			(effects
				(font
					(size 1 1)
					(thickness 0.15)
				)
			)
		)
		(property "Dielectric" ""
			(at 349.8 331 0)
			(layer "F.Fab")
			(hide yes)
			(effects
				(font
					(size 1 1)
					(thickness 0.15)
				)
			)
		)
		(property "License" "Apache-2.0"
			(at 349.8 331 0)
			(layer "F.Fab")
			(hide yes)
			(effects
				(font
					(size 1 1)
					(thickness 0.15)
				)
			)
		)
		(property "MPN" "GRM188R60J226MEA0D"
			(at 349.8 331 0)
			(layer "F.Fab")
			(hide yes)
			(effects
				(font
					(size 1 1)
					(thickness 0.15)
				)
			)
		)
		(property "Manufacturer" "Murata"
			(at 349.8 331 0)
			(layer "F.Fab")
			(hide yes)
			(effects
				(font
					(size 1 1)
					(thickness 0.15)
				)
			)
		)
		(property "Val" "22u"
			(at 349.8 331 0)
			(layer "F.Fab")
			(hide yes)
			(effects
				(font
					(size 1 1)
					(thickness 0.15)
				)
			)
		)
		(property "Voltage" ""
			(at 349.8 331 0)
			(layer "F.Fab")
			(hide yes)
			(effects
				(font
					(size 1 1)
					(thickness 0.15)
				)
			)
		)
		(sheetname "DC-DC Converters")
		(sheetfile "dc-dc.kicad_sch")
		(attr smd)
		(fp_line
			(start -0.15 0.4)
			(end 0.15 0.4)
			(stroke
				(width 0.15)
				(type solid)
			)
			(layer "F.SilkS")
		)
		(fp_line
			(start -0.15 -0.4)
			(end 0.15 -0.4)
			(stroke
				(width 0.15)
				(type solid)
			)
			(layer "F.SilkS")
		)
		(fp_rect
			(start -1.25 -0.65)
			(end 1.25 0.65)
			(stroke
				(width 0.05)
				(type solid)
			)
			(fill no)
			(layer "F.CrtYd")
		)
		(fp_rect
			(start -0.8 -0.4)
			(end 0.8 0.4)
			(stroke
				(width 0.15)
				(type solid)
			)
			(fill no)
			(layer "F.Fab")
		)
		(pad "1" smd roundrect
			(at -0.7 0 180)
			(size 0.8 1)
			(layers "F.Cu" "F.Mask" "F.Paste")
			(roundrect_rratio 0.2)
			(net 1 "GND")
			(pintype "passive")
		)
		(pad "2" smd roundrect
			(at 0.7 0 180)
			(size 0.8 1)
			(layers "F.Cu" "F.Mask" "F.Paste")
			(roundrect_rratio 0.2)
			(net 735 "/DC-DC Converters/3V3_local")
			(pintype "passive")
		)
	)
)
